# S9S_MB_2U (Grand Teton) — schematic netlist excerpt (pin names and nets, part order shuffled) for the footprints in the layout excerpt that follows; sources: Cadence DE-HDL packaged netlist, KiCad conversion of 03242023_DA0F0TMBIJ0_F0T_Motherboard_J_brd_V01_OCP.brd

PC1215  Q_CAPP  100UF 16V 20% OSCON  pkg SMLF  page 262 : A = SW_P12V_AUX_P1V05_PCH_AUX_FLT ; B = GND
C690  Q_CAP_DIFFBUS  DIFF BUS_0.22UF 6.3V 20% X6S  pkg C0201  page 177 : \1\ = P5E_CPU1_PE4_TX_C_DN<9> ; \2\ = P5E_CPU1_PE4_TX_DN<9>

(kicad_pcb
	(version 20260206)
	(generator "pcbnew")
	(generator_version "10.0")
	(general
		(thickness 1.6)
		(legacy_teardrops no)
	)
	(paper "A4")
	(title_block
		(title "03242023_DA0F0TMBIJ0_F0T_Motherboard_J_brd_V01_OCP.brd")
		(comment 1 "Grand Teton / footprints 2810-2811 of 6105")
	)
	(layers
		(0 "F.Cu" signal "TOP")
		(4 "In1.Cu" signal "GND")
		(6 "In2.Cu" signal "IN1")
		(8 "In3.Cu" signal "GND1")
		(10 "In4.Cu" signal "IN2")
		(12 "In5.Cu" signal "GND2")
		(14 "In6.Cu" signal "IN3")
		(16 "In7.Cu" signal "GND3")
		(18 "In8.Cu" signal "VCC")
		(20 "In9.Cu" signal "VCC1")
		(22 "In10.Cu" signal "GND4")
		(24 "In11.Cu" signal "IN4")
		(26 "In12.Cu" signal "GND5")
		(28 "In13.Cu" signal "IN5")
		(30 "In14.Cu" signal "GND6")
		(32 "In15.Cu" signal "IN6")
		(34 "In16.Cu" signal "GND7")
		(2 "B.Cu" signal "BOTTOM")
		(9 "F.Adhes" user "F.Adhesive")
		(11 "B.Adhes" user "B.Adhesive")
		(13 "F.Paste" user "Package Geometry/Pastemask Top")
		(15 "B.Paste" user "Package Geometry/Pastemask Bottom")
		(5 "F.SilkS" user "Ref Des/Silkscreen Top")
		(7 "B.SilkS" user "Ref Des/Silkscreen Bottom")
		(1 "F.Mask" user "Board Geometry/Soldermask Top")
		(3 "B.Mask" user "Board Geometry/Soldermask Bottom")
		(17 "Dwgs.User" user "User.Drawings")
		(19 "Cmts.User" user "User.Comments")
		(21 "Eco1.User" user "User.Eco1")
		(23 "Eco2.User" user "User.Eco2")
		(25 "Edge.Cuts" user "Board Geometry/Outline")
		(27 "Margin" user)
		(31 "F.CrtYd" user "Package Geometry/Place Bound Top")
		(29 "B.CrtYd" user "Package Geometry/Place Bound Bottom")
		(35 "F.Fab" user "Ref Des/Assembly Top")
		(33 "B.Fab" user "Ref Des/Assembly Bottom")
	)
	(footprint ""
		(layer "F.Cu")
		(at 255.493012 -76.222098 90)
		(property "Reference" "PC1215"
			(at 0 0 90)
			(layer "F.SilkS")
			(hide yes)
			(effects
				(font
					(size 1.27 1.27)
				)
			)
		)
		(property "Value" ""
			(at 0 0 90)
			(layer "F.Fab")
			(effects
				(font
					(size 1.27 1.27)
				)
			)
		)
		(duplicate_pad_numbers_are_jumpers no)
		(fp_line
			(start 2.750058 -2.750058)
			(end -1.988058 -2.750058)
			(stroke
				(width 0.1524)
				(type default)
			)
			(layer "F.SilkS")
		)
		(fp_line
			(start -1.988058 -2.750058)
			(end -2.750058 -1.988058)
			(stroke
				(width 0.1524)
				(type default)
			)
			(layer "F.SilkS")
		)
		(fp_line
			(start -2.750058 -1.988058)
			(end -2.750058 -0.9398)
			(stroke
				(width 0.1524)
				(type default)
			)
			(layer "F.SilkS")
		)
		(fp_line
			(start 2.750058 -0.9398)
			(end 2.750058 -2.750058)
			(stroke
				(width 0.1524)
				(type default)
			)
			(layer "F.SilkS")
		)
		(fp_line
			(start -2.750058 0.9398)
			(end -2.750058 1.988058)
			(stroke
				(width 0.1524)
				(type default)
			)
			(layer "F.SilkS")
		)
		(fp_line
			(start -2.750058 1.988058)
			(end -1.988058 2.750058)
			(stroke
				(width 0.1524)
				(type default)
			)
			(layer "F.SilkS")
		)
		(fp_line
			(start 2.750058 2.750058)
			(end 2.750058 0.9398)
			(stroke
				(width 0.1524)
				(type default)
			)
			(layer "F.SilkS")
		)
		(fp_line
			(start -1.988058 2.750058)
			(end 2.750058 2.750058)
			(stroke
				(width 0.1524)
				(type default)
			)
			(layer "F.SilkS")
		)
		(fp_line
			(start 2.750058 -2.750058)
			(end -2.750058 -2.750058)
			(stroke
				(width 0.1)
				(type default)
			)
			(layer "F.Fab")
		)
		(fp_line
			(start -2.750058 -2.750058)
			(end -2.750058 2.750058)
			(stroke
				(width 0.1)
				(type default)
			)
			(layer "F.Fab")
		)
		(fp_line
			(start 2.750058 2.750058)
			(end 2.750058 -2.750058)
			(stroke
				(width 0.1)
				(type default)
			)
			(layer "F.Fab")
		)
		(fp_line
			(start -2.750058 2.750058)
			(end 2.750058 2.750058)
			(stroke
				(width 0.1)
				(type default)
			)
			(layer "F.Fab")
		)
		(pad "1" smd rect
			(at -2.199894 0 180)
			(size 1.6002 3.0226)
			(layers "F.Cu" "F.Mask" "F.Paste")
			(net "SW_P12V_AUX_P1V05_PCH_AUX_FLT")
		)
		(pad "2" smd rect
			(at 2.199894 0 180)
			(size 1.6002 3.0226)
			(layers "F.Cu" "F.Mask" "F.Paste")
			(net "GND")
		)
	)
	(footprint ""
		(layer "F.Cu")
		(at 76.869798 -408.517344 -90)
		(property "Reference" "C690"
			(at 0 0 270)
			(layer "F.SilkS")
			(hide yes)
			(effects
				(font
					(size 1.27 1.27)
				)
			)
		)
		(property "Value" ""
			(at 0 0 270)
			(layer "F.Fab")
			(effects
				(font
					(size 1.27 1.27)
				)
			)
		)
		(duplicate_pad_numbers_are_jumpers no)
		(fp_line
			(start -0.299974 0.150114)
			(end -0.299974 -0.150114)
			(stroke
				(width 0.1)
				(type default)
			)
			(layer "F.Fab")
		)
		(fp_line
			(start 0.299974 0.150114)
			(end -0.299974 0.150114)
			(stroke
				(width 0.1)
				(type default)
			)
			(layer "F.Fab")
		)
		(fp_line
			(start -0.299974 -0.150114)
			(end 0.299974 -0.150114)
			(stroke
				(width 0.1)
				(type default)
			)
			(layer "F.Fab")
		)
		(fp_line
			(start 0.299974 -0.150114)
			(end 0.299974 0.150114)
			(stroke
				(width 0.1)
				(type default)
			)
			(layer "F.Fab")
		)
		(pad "1" smd rect
			(at -0.2667 0 270)
			(size 0.3048 0.381)
			(layers "F.Cu" "F.Mask" "F.Paste")
			(net "P5E_CPU1_PE4_TX_C_DN<9>")
		)
		(pad "2" smd rect
			(at 0.2667 0 270)
			(size 0.3048 0.381)
			(layers "F.Cu" "F.Mask" "F.Paste")
			(net "P5E_CPU1_PE4_TX_DN<9>")
		)
	)
)
